(kicad_pcb
	(version 20260206)
	(generator "pcbnew")
	(generator_version "10.0")
	(general
		(thickness 1.6)
		(legacy_teardrops no)
	)
	(paper "A4")
	(title_block
		(title "03242023_DA0F0TMBIJ0_F0T_Motherboard_J_brd_V01_OCP.brd")
		(comment 1 "Grand Teton / footprints 4970-4976 of 6105")
	)
	(layers
		(0 "F.Cu" signal "TOP")
		(4 "In1.Cu" signal "GND")
		(6 "In2.Cu" signal "IN1")
		(8 "In3.Cu" signal "GND1")
		(10 "In4.Cu" signal "IN2")
		(12 "In5.Cu" signal "GND2")
		(14 "In6.Cu" signal "IN3")
		(16 "In7.Cu" signal "GND3")
		(18 "In8.Cu" signal "VCC")
		(20 "In9.Cu" signal "VCC1")
		(22 "In10.Cu" signal "GND4")
		(24 "In11.Cu" signal "IN4")
		(26 "In12.Cu" signal "GND5")
		(28 "In13.Cu" signal "IN5")
		(30 "In14.Cu" signal "GND6")
		(32 "In15.Cu" signal "IN6")
		(34 "In16.Cu" signal "GND7")
		(2 "B.Cu" signal "BOTTOM")
		(9 "F.Adhes" user "F.Adhesive")
		(11 "B.Adhes" user "B.Adhesive")
		(13 "F.Paste" user "Package Geometry/Pastemask Top")
		(15 "B.Paste" user "Package Geometry/Pastemask Bottom")
		(5 "F.SilkS" user "Ref Des/Silkscreen Top")
		(7 "B.SilkS" user "Ref Des/Silkscreen Bottom")
		(1 "F.Mask" user "Board Geometry/Soldermask Top")
		(3 "B.Mask" user "Board Geometry/Soldermask Bottom")
		(17 "Dwgs.User" user "User.Drawings")
		(19 "Cmts.User" user "User.Comments")
		(21 "Eco1.User" user "User.Eco1")
		(23 "Eco2.User" user "User.Eco2")
		(25 "Edge.Cuts" user "Board Geometry/Outline")
		(27 "Margin" user)
		(31 "F.CrtYd" user "Package Geometry/Place Bound Top")
		(29 "B.CrtYd" user "Package Geometry/Place Bound Bottom")
		(35 "F.Fab" user "Ref Des/Assembly Top")
		(33 "B.Fab" user "Ref Des/Assembly Bottom")
	)
	(footprint ""
		(layer "B.Cu")
		(at 430.577244 -123.648724 180)
		(property "Reference" "PR1311"
			(at 0 0 0)
			(layer "B.SilkS")
			(hide yes)
			(effects
				(font
					(size 1.27 1.27)
				)
				(justify mirror)
			)
		)
		(property "Value" ""
			(at 0 0 0)
			(layer "B.Fab")
			(effects
				(font
					(size 1.27 1.27)
				)
				(justify mirror)
			)
		)
		(duplicate_pad_numbers_are_jumpers no)
		(fp_line
			(start 0.7874 0.4064)
			(end 0.7874 -0.4064)
			(stroke
				(width 0.1524)
				(type default)
			)
			(layer "B.SilkS")
		)
		(fp_line
			(start 0.7874 -0.4064)
			(end -0.7874 -0.4064)
			(stroke
				(width 0.1524)
				(type default)
			)
			(layer "B.SilkS")
		)
		(fp_line
			(start -0.7874 0.4064)
			(end 0.7874 0.4064)
			(stroke
				(width 0.1524)
				(type default)
			)
			(layer "B.SilkS")
		)
		(fp_line
			(start -0.7874 -0.4064)
			(end -0.7874 0.4064)
			(stroke
				(width 0.1524)
				(type default)
			)
			(layer "B.SilkS")
		)
		(fp_line
			(start 0.67945 0.3048)
			(end 0.67945 -0.305054)
			(stroke
				(width 0.1)
				(type default)
			)
			(layer "B.Fab")
		)
		(fp_line
			(start 0.67945 -0.305054)
			(end 0.12065 -0.305054)
			(stroke
				(width 0.1)
				(type default)
			)
			(layer "B.Fab")
		)
		(fp_line
			(start 0.12065 0.3048)
			(end 0.67945 0.3048)
			(stroke
				(width 0.1)
				(type default)
			)
			(layer "B.Fab")
		)
		(fp_line
			(start 0.12065 0.2794)
			(end 0.12065 0.3048)
			(stroke
				(width 0.1)
				(type default)
			)
			(layer "B.Fab")
		)
		(fp_line
			(start 0.12065 -0.2794)
			(end -0.12065 -0.2794)
			(stroke
				(width 0.1)
				(type default)
			)
			(layer "B.Fab")
		)
		(fp_line
			(start 0.12065 -0.305054)
			(end 0.12065 -0.2794)
			(stroke
				(width 0.1)
				(type default)
			)
			(layer "B.Fab")
		)
		(fp_line
			(start -0.120396 0.3048)
			(end -0.120396 0.2794)
			(stroke
				(width 0.1)
				(type default)
			)
			(layer "B.Fab")
		)
		(fp_line
			(start -0.120396 0.2794)
			(end 0.12065 0.2794)
			(stroke
				(width 0.1)
				(type default)
			)
			(layer "B.Fab")
		)
		(fp_line
			(start -0.12065 -0.2794)
			(end -0.12065 -0.3048)
			(stroke
				(width 0.1)
				(type default)
			)
			(layer "B.Fab")
		)
		(fp_line
			(start -0.12065 -0.3048)
			(end -0.67945 -0.3048)
			(stroke
				(width 0.1)
				(type default)
			)
			(layer "B.Fab")
		)
		(fp_line
			(start -0.67945 0.3048)
			(end -0.120396 0.3048)
			(stroke
				(width 0.1)
				(type default)
			)
			(layer "B.Fab")
		)
		(fp_line
			(start -0.67945 -0.3048)
			(end -0.67945 0.3048)
			(stroke
				(width 0.1)
				(type default)
			)
			(layer "B.Fab")
		)
		(pad "1" smd circle
			(at 0.40005 0)
			(size 0 0)
			(layers "B.Cu" "B.Mask" "B.Paste")
			(net "PVCCD_HV_CPU0_ISYS_R")
		)
		(pad "2" smd circle
			(at -0.40005 0)
			(size 0 0)
			(layers "B.Cu" "B.Mask" "B.Paste")
			(net "GND")
		)
	)
	(footprint ""
		(layer "B.Cu")
		(at 338.422234 -136.479534)
		(property "Reference" "R1015"
			(at 0 0 0)
			(layer "B.SilkS")
			(hide yes)
			(effects
				(font
					(size 1.27 1.27)
				)
				(justify mirror)
			)
		)
		(property "Value" ""
			(at 0 0 0)
			(layer "B.Fab")
			(effects
				(font
					(size 1.27 1.27)
				)
				(justify mirror)
			)
		)
		(duplicate_pad_numbers_are_jumpers no)
		(fp_line
			(start -0.7874 -0.4064)
			(end -0.7874 0.4064)
			(stroke
				(width 0.1524)
				(type default)
			)
			(layer "B.SilkS")
		)
		(fp_line
			(start -0.7874 0.4064)
			(end 0.7874 0.4064)
			(stroke
				(width 0.1524)
				(type default)
			)
			(layer "B.SilkS")
		)
		(fp_line
			(start -0.630174 -0.4064)
			(end -0.7874 -0.4064)
			(stroke
				(width 0.1524)
				(type default)
			)
			(layer "B.SilkS")
		)
		(fp_line
			(start 0.7874 -0.4064)
			(end -0.195834 -0.4064)
			(stroke
				(width 0.1524)
				(type default)
			)
			(layer "B.SilkS")
		)
		(fp_line
			(start 0.7874 -0.208534)
			(end 0.7874 -0.4064)
			(stroke
				(width 0.1524)
				(type default)
			)
			(layer "B.SilkS")
		)
		(fp_line
			(start 0.7874 0.4064)
			(end 0.7874 0.220726)
			(stroke
				(width 0.1524)
				(type default)
			)
			(layer "B.SilkS")
		)
		(fp_line
			(start -0.67945 -0.3048)
			(end -0.67945 0.3048)
			(stroke
				(width 0.1)
				(type default)
			)
			(layer "B.Fab")
		)
		(fp_line
			(start -0.67945 0.3048)
			(end -0.120396 0.3048)
			(stroke
				(width 0.1)
				(type default)
			)
			(layer "B.Fab")
		)
		(fp_line
			(start -0.12065 -0.3048)
			(end -0.67945 -0.3048)
			(stroke
				(width 0.1)
				(type default)
			)
			(layer "B.Fab")
		)
		(fp_line
			(start -0.12065 -0.2794)
			(end -0.12065 -0.3048)
			(stroke
				(width 0.1)
				(type default)
			)
			(layer "B.Fab")
		)
		(fp_line
			(start -0.120396 0.2794)
			(end 0.12065 0.2794)
			(stroke
				(width 0.1)
				(type default)
			)
			(layer "B.Fab")
		)
		(fp_line
			(start -0.120396 0.3048)
			(end -0.120396 0.2794)
			(stroke
				(width 0.1)
				(type default)
			)
			(layer "B.Fab")
		)
		(fp_line
			(start 0.12065 -0.305054)
			(end 0.12065 -0.2794)
			(stroke
				(width 0.1)
				(type default)
			)
			(layer "B.Fab")
		)
		(fp_line
			(start 0.12065 -0.2794)
			(end -0.12065 -0.2794)
			(stroke
				(width 0.1)
				(type default)
			)
			(layer "B.Fab")
		)
		(fp_line
			(start 0.12065 0.2794)
			(end 0.12065 0.3048)
			(stroke
				(width 0.1)
				(type default)
			)
			(layer "B.Fab")
		)
		(fp_line
			(start 0.12065 0.3048)
			(end 0.67945 0.3048)
			(stroke
				(width 0.1)
				(type default)
			)
			(layer "B.Fab")
		)
		(fp_line
			(start 0.67945 -0.305054)
			(end 0.12065 -0.305054)
			(stroke
				(width 0.1)
				(type default)
			)
			(layer "B.Fab")
		)
		(fp_line
			(start 0.67945 0.3048)
			(end 0.67945 -0.305054)
			(stroke
				(width 0.1)
				(type default)
			)
			(layer "B.Fab")
		)
		(pad "1" smd rect
			(at 0.40005 0)
			(size 0.4572 0.508)
			(layers "B.Cu" "B.Mask" "B.Paste")
			(net "CLK_25M_PCH_CPU0_DN")
		)
		(pad "2" smd rect
			(at -0.40005 0)
			(size 0.4572 0.508)
			(layers "B.Cu" "B.Mask" "B.Paste")
			(net "CLK_25M_NSSC_CPU0_DN")
		)
	)
	(footprint ""
		(layer "B.Cu")
		(at 107.457494 -248.49836 -90)
		(property "Reference" "C339"
			(at 0 0 90)
			(layer "B.SilkS")
			(hide yes)
			(effects
				(font
					(size 1.27 1.27)
				)
				(justify mirror)
			)
		)
		(property "Value" ""
			(at 0 0 90)
			(layer "B.Fab")
			(effects
				(font
					(size 1.27 1.27)
				)
				(justify mirror)
			)
		)
		(duplicate_pad_numbers_are_jumpers no)
		(fp_line
			(start -1.524 0.762)
			(end 1.524 0.762)
			(stroke
				(width 0.1524)
				(type default)
			)
			(layer "B.SilkS")
		)
		(fp_line
			(start 1.524 0.762)
			(end 1.524 -0.762)
			(stroke
				(width 0.1524)
				(type default)
			)
			(layer "B.SilkS")
		)
		(fp_line
			(start -1.524 -0.762)
			(end -1.524 0.762)
			(stroke
				(width 0.1524)
				(type default)
			)
			(layer "B.SilkS")
		)
		(fp_line
			(start 1.524 -0.762)
			(end -1.524 -0.762)
			(stroke
				(width 0.1524)
				(type default)
			)
			(layer "B.SilkS")
		)
		(fp_line
			(start -1.1049 0.724916)
			(end -1.1049 -0.724916)
			(stroke
				(width 0.1)
				(type default)
			)
			(layer "B.Fab")
		)
		(fp_line
			(start 1.1049 0.724916)
			(end -1.1049 0.724916)
			(stroke
				(width 0.1)
				(type default)
			)
			(layer "B.Fab")
		)
		(fp_line
			(start -1.1049 -0.724916)
			(end 1.1049 -0.724916)
			(stroke
				(width 0.1)
				(type default)
			)
			(layer "B.Fab")
		)
		(fp_line
			(start 1.1049 -0.724916)
			(end 1.1049 0.724916)
			(stroke
				(width 0.1)
				(type default)
			)
			(layer "B.Fab")
		)
		(pad "1" smd rect
			(at 0.889 0 270)
			(size 1.016 1.27)
			(layers "B.Cu" "B.Mask" "B.Paste")
			(net "PVCCIN_CPU1")
		)
		(pad "2" smd rect
			(at -0.889 0 270)
			(size 1.016 1.27)
			(layers "B.Cu" "B.Mask" "B.Paste")
			(net "GND")
		)
	)
	(footprint ""
		(layer "B.Cu")
		(at 338.045552 -190.756286 -90)
		(property "Reference" "R680"
			(at 0 0 90)
			(layer "B.SilkS")
			(hide yes)
			(effects
				(font
					(size 1.27 1.27)
				)
				(justify mirror)
			)
		)
		(property "Value" ""
			(at 0 0 90)
			(layer "B.Fab")
			(effects
				(font
					(size 1.27 1.27)
				)
				(justify mirror)
			)
		)
		(duplicate_pad_numbers_are_jumpers no)
		(fp_line
			(start -0.7874 0.4064)
			(end 0.7874 0.4064)
			(stroke
				(width 0.1524)
				(type default)
			)
			(layer "B.SilkS")
		)
		(fp_line
			(start 0.7874 0.4064)
			(end 0.7874 -0.4064)
			(stroke
				(width 0.1524)
				(type default)
			)
			(layer "B.SilkS")
		)
		(fp_line
			(start -0.7874 -0.4064)
			(end -0.7874 0.4064)
			(stroke
				(width 0.1524)
				(type default)
			)
			(layer "B.SilkS")
		)
		(fp_line
			(start 0.7874 -0.4064)
			(end -0.7874 -0.4064)
			(stroke
				(width 0.1524)
				(type default)
			)
			(layer "B.SilkS")
		)
		(fp_line
			(start -0.67945 0.3048)
			(end -0.120396 0.3048)
			(stroke
				(width 0.1)
				(type default)
			)
			(layer "B.Fab")
		)
		(fp_line
			(start -0.120396 0.3048)
			(end -0.120396 0.2794)
			(stroke
				(width 0.1)
				(type default)
			)
			(layer "B.Fab")
		)
		(fp_line
			(start 0.12065 0.3048)
			(end 0.67945 0.3048)
			(stroke
				(width 0.1)
				(type default)
			)
			(layer "B.Fab")
		)
		(fp_line
			(start 0.67945 0.3048)
			(end 0.67945 -0.305054)
			(stroke
				(width 0.1)
				(type default)
			)
			(layer "B.Fab")
		)
		(fp_line
			(start -0.120396 0.2794)
			(end 0.12065 0.2794)
			(stroke
				(width 0.1)
				(type default)
			)
			(layer "B.Fab")
		)
		(fp_line
			(start 0.12065 0.2794)
			(end 0.12065 0.3048)
			(stroke
				(width 0.1)
				(type default)
			)
			(layer "B.Fab")
		)
		(fp_line
			(start -0.12065 -0.2794)
			(end -0.12065 -0.3048)
			(stroke
				(width 0.1)
				(type default)
			)
			(layer "B.Fab")
		)
		(fp_line
			(start 0.12065 -0.2794)
			(end -0.12065 -0.2794)
			(stroke
				(width 0.1)
				(type default)
			)
			(layer "B.Fab")
		)
		(fp_line
			(start -0.67945 -0.3048)
			(end -0.67945 0.3048)
			(stroke
				(width 0.1)
				(type default)
			)
			(layer "B.Fab")
		)
		(fp_line
			(start -0.12065 -0.3048)
			(end -0.67945 -0.3048)
			(stroke
				(width 0.1)
				(type default)
			)
			(layer "B.Fab")
		)
		(fp_line
			(start 0.12065 -0.305054)
			(end 0.12065 -0.2794)
			(stroke
				(width 0.1)
				(type default)
			)
			(layer "B.Fab")
		)
		(fp_line
			(start 0.67945 -0.305054)
			(end 0.12065 -0.305054)
			(stroke
				(width 0.1)
				(type default)
			)
			(layer "B.Fab")
		)
		(pad "1" smd circle
			(at 0.40005 0 90)
			(size 0 0)
			(layers "B.Cu" "B.Mask" "B.Paste")
			(net "PVNN_TERM_CPU0")
		)
		(pad "2" smd circle
			(at -0.40005 0 90)
			(size 0 0)
			(layers "B.Cu" "B.Mask" "B.Paste")
			(net "I3C_SPD_DDRABCD_CPU0_SDA")
		)
	)
	(footprint ""
		(layer "B.Cu")
		(at 351.536508 -237.709202 -90)
		(property "Reference" "C1407"
			(at 0 0 90)
			(layer "B.SilkS")
			(hide yes)
			(effects
				(font
					(size 1.27 1.27)
				)
				(justify mirror)
			)
		)
		(property "Value" ""
			(at 0 0 90)
			(layer "B.Fab")
			(effects
				(font
					(size 1.27 1.27)
				)
				(justify mirror)
			)
		)
		(duplicate_pad_numbers_are_jumpers no)
		(fp_line
			(start -1.2954 0.5842)
			(end 1.2954 0.5842)
			(stroke
				(width 0.1524)
				(type default)
			)
			(layer "B.SilkS")
		)
		(fp_line
			(start 1.2954 0.5842)
			(end 1.2954 -0.5842)
			(stroke
				(width 0.1524)
				(type default)
			)
			(layer "B.SilkS")
		)
		(fp_line
			(start -1.2954 -0.5842)
			(end -1.2954 0.5842)
			(stroke
				(width 0.1524)
				(type default)
			)
			(layer "B.SilkS")
		)
		(fp_line
			(start 0 -0.5842)
			(end 0 0.5842)
			(stroke
				(width 0.1524)
				(type default)
			)
			(layer "B.SilkS")
		)
		(fp_line
			(start 1.2954 -0.5842)
			(end -1.2954 -0.5842)
			(stroke
				(width 0.1524)
				(type default)
			)
			(layer "B.SilkS")
		)
		(fp_line
			(start -0.8636 0.4572)
			(end 0.8636 0.4572)
			(stroke
				(width 0.1)
				(type default)
			)
			(layer "B.Fab")
		)
		(fp_line
			(start 0.8636 0.4572)
			(end 0.8636 0.4064)
			(stroke
				(width 0.1)
				(type default)
			)
			(layer "B.Fab")
		)
		(fp_line
			(start -1.1938 0.4064)
			(end -0.8636 0.4064)
			(stroke
				(width 0.1)
				(type default)
			)
			(layer "B.Fab")
		)
		(fp_line
			(start -0.8636 0.4064)
			(end -0.8636 0.4572)
			(stroke
				(width 0.1)
				(type default)
			)
			(layer "B.Fab")
		)
		(fp_line
			(start 0.8636 0.4064)
			(end 1.1938 0.4064)
			(stroke
				(width 0.1)
				(type default)
			)
			(layer "B.Fab")
		)
		(fp_line
			(start 1.1938 0.4064)
			(end 1.1938 -0.4064)
			(stroke
				(width 0.1)
				(type default)
			)
			(layer "B.Fab")
		)
		(fp_line
			(start -1.1938 -0.4064)
			(end -1.1938 0.4064)
			(stroke
				(width 0.1)
				(type default)
			)
			(layer "B.Fab")
		)
		(fp_line
			(start -0.8636 -0.4064)
			(end -1.1938 -0.4064)
			(stroke
				(width 0.1)
				(type default)
			)
			(layer "B.Fab")
		)
		(fp_line
			(start 0.8636 -0.4064)
			(end 0.8636 -0.4572)
			(stroke
				(width 0.1)
				(type default)
			)
			(layer "B.Fab")
		)
		(fp_line
			(start 1.1938 -0.4064)
			(end 0.8636 -0.4064)
			(stroke
				(width 0.1)
				(type default)
			)
			(layer "B.Fab")
		)
		(fp_line
			(start -0.8636 -0.4572)
			(end -0.8636 -0.4064)
			(stroke
				(width 0.1)
				(type default)
			)
			(layer "B.Fab")
		)
		(fp_line
			(start 0.8636 -0.4572)
			(end -0.8636 -0.4572)
			(stroke
				(width 0.1)
				(type default)
			)
			(layer "B.Fab")
		)
		(pad "1" smd rect
			(at 0.7366 0 180)
			(size 0.7112 0.8128)
			(layers "B.Cu" "B.Mask" "B.Paste")
			(net "PVNN_MAIN_CPU0")
		)
		(pad "2" smd rect
			(at -0.7366 0 180)
			(size 0.7112 0.8128)
			(layers "B.Cu" "B.Mask" "B.Paste")
			(net "GND")
		)
	)
	(footprint ""
		(layer "B.Cu")
		(at 25.277064 -175.824642 -90)
		(property "Reference" "R2584"
			(at 0 0 90)
			(layer "B.SilkS")
			(hide yes)
			(effects
				(font
					(size 1.27 1.27)
				)
				(justify mirror)
			)
		)
		(property "Value" ""
			(at 0 0 90)
			(layer "B.Fab")
			(effects
				(font
					(size 1.27 1.27)
				)
				(justify mirror)
			)
		)
		(duplicate_pad_numbers_are_jumpers no)
		(fp_line
			(start -0.7874 0.4064)
			(end 0.7874 0.4064)
			(stroke
				(width 0.1524)
				(type default)
			)
			(layer "B.SilkS")
		)
		(fp_line
			(start 0.7874 0.4064)
			(end 0.7874 -0.4064)
			(stroke
				(width 0.1524)
				(type default)
			)
			(layer "B.SilkS")
		)
		(fp_line
			(start -0.7874 -0.4064)
			(end -0.7874 0.4064)
			(stroke
				(width 0.1524)
				(type default)
			)
			(layer "B.SilkS")
		)
		(fp_line
			(start 0.7874 -0.4064)
			(end -0.7874 -0.4064)
			(stroke
				(width 0.1524)
				(type default)
			)
			(layer "B.SilkS")
		)
		(fp_line
			(start -0.67945 0.3048)
			(end -0.120396 0.3048)
			(stroke
				(width 0.1)
				(type default)
			)
			(layer "B.Fab")
		)
		(fp_line
			(start -0.120396 0.3048)
			(end -0.120396 0.2794)
			(stroke
				(width 0.1)
				(type default)
			)
			(layer "B.Fab")
		)
		(fp_line
			(start 0.12065 0.3048)
			(end 0.67945 0.3048)
			(stroke
				(width 0.1)
				(type default)
			)
			(layer "B.Fab")
		)
		(fp_line
			(start 0.67945 0.3048)
			(end 0.67945 -0.305054)
			(stroke
				(width 0.1)
				(type default)
			)
			(layer "B.Fab")
		)
		(fp_line
			(start -0.120396 0.2794)
			(end 0.12065 0.2794)
			(stroke
				(width 0.1)
				(type default)
			)
			(layer "B.Fab")
		)
		(fp_line
			(start 0.12065 0.2794)
			(end 0.12065 0.3048)
			(stroke
				(width 0.1)
				(type default)
			)
			(layer "B.Fab")
		)
		(fp_line
			(start -0.12065 -0.2794)
			(end -0.12065 -0.3048)
			(stroke
				(width 0.1)
				(type default)
			)
			(layer "B.Fab")
		)
		(fp_line
			(start 0.12065 -0.2794)
			(end -0.12065 -0.2794)
			(stroke
				(width 0.1)
				(type default)
			)
			(layer "B.Fab")
		)
		(fp_line
			(start -0.67945 -0.3048)
			(end -0.67945 0.3048)
			(stroke
				(width 0.1)
				(type default)
			)
			(layer "B.Fab")
		)
		(fp_line
			(start -0.12065 -0.3048)
			(end -0.67945 -0.3048)
			(stroke
				(width 0.1)
				(type default)
			)
			(layer "B.Fab")
		)
		(fp_line
			(start 0.12065 -0.305054)
			(end 0.12065 -0.2794)
			(stroke
				(width 0.1)
				(type default)
			)
			(layer "B.Fab")
		)
		(fp_line
			(start 0.67945 -0.305054)
			(end 0.12065 -0.305054)
			(stroke
				(width 0.1)
				(type default)
			)
			(layer "B.Fab")
		)
		(pad "1" smd circle
			(at 0.40005 0 90)
			(size 0 0)
			(layers "B.Cu" "B.Mask" "B.Paste")
			(net "P3V3_AUX")
		)
		(pad "2" smd circle
			(at -0.40005 0 90)
			(size 0 0)
			(layers "B.Cu" "B.Mask" "B.Paste")
			(net "PWRGD_PVNN_MAIN_CPU1_R")
		)
	)
	(footprint ""
		(layer "B.Cu")
		(at 368.398298 -359.586276 -90)
		(property "Reference" "PJ64"
			(at -3.236722 -3.587242 0)
			(unlocked yes)
			(layer "B.SilkS")
			(effects
				(font
					(size 0.7874 0.5842)
					(thickness 0.1524)
				)
				(justify left mirror)
			)
		)
		(property "Value" ""
			(at 0 0 90)
			(layer "B.Fab")
			(effects
				(font
					(size 1.27 1.27)
				)
				(justify mirror)
			)
		)
		(duplicate_pad_numbers_are_jumpers no)
		(pad "1" smd circle
			(at 0.7493 0)
			(size 0 0)
			(layers "B.Cu" "B.Mask" "B.Paste")
			(net "SH_PVPP_HBM_CPU0_P")
		)
		(pad "2" smd rect
			(at -0.7493 0 180)
			(size 0.7112 0.8128)
			(layers "B.Cu" "B.Mask" "B.Paste")
			(net "PVPP_HBM_CPU0")
		)
		(zone
			(layer "B.Cu")
			(hatch none 0.5)
			(connect_pads
				(clearance 0)
			)
			(min_thickness 0.25)
			(keepout
				(tracks allowed)
				(vias not_allowed)
				(pads allowed)
				(copperpour not_allowed)
				(footprints allowed)
			)
			(placement
				(enabled no)
				(sheetname "")
			)
			(fill
				(thermal_gap 0.5)
				(thermal_bridge_width 0.5)
				(island_removal_mode 0)
			)
			(polygon
				(pts
					(xy 367.987072 -358.405176) (xy 368.804698 -358.405176) (xy 368.804698 -360.792776) (xy 367.987072 -360.792776)
				)
			)
		)
	)
)
